# BASEBOARD_FAB2 (Tioga Pass) — schematic netlist excerpt (pin names and nets, part order shuffled) for the footprints in the layout excerpt that follows; sources: Cadence DE-HDL packaged netlist, KiCad conversion of Wiwynn_Tioga_Pass_MB.brd

J6L2  SCONN288_H44441003  SCONN  pkg PIP  page 52
  \12v\(1)  = P12V_NVDIMM_DEF
  VSS(93)  = GND
  DQ(4)  = M_E_DQ<4>
  VSS(92)  = GND
  DQ(0)  = M_E_DQ<0>
  VSS(91)  = GND
  DQS9P  = M_E_DQS_DP<9>
  DQS9N  = M_E_DQS_DN<9>
  VSS(90)  = GND
  DQ(6)  = M_E_DQ<6>
  VSS(89)  = GND
  DQ(2)  = M_E_DQ<2>
  VSS(88)  = GND
  DQ(12)  = M_E_DQ<12>
  VSS(87)  = GND
  DQ(8)  = M_E_DQ<8>
  VSS(86)  = GND
  DQS10P  = M_E_DQS_DP<10>
  DQS10N  = M_E_DQS_DN<10>
  VSS(85)  = GND
  DQ(14)  = M_E_DQ<14>
  VSS(84)  = GND
  DQ(10)  = M_E_DQ<10>
  VSS(83)  = GND
  DQ(20)  = M_E_DQ<20>
  VSS(82)  = GND
  DQ(16)  = M_E_DQ<16>
  VSS(81)  = GND
  DQS11P  = M_E_DQS_DP<11>
  DQS11N  = M_E_DQS_DN<11>
  VSS(80)  = GND
  DQ(22)  = M_E_DQ<22>
  VSS(79)  = GND
  DQ(18)  = M_E_DQ<18>
  VSS(78)  = GND
  DQ(28)  = M_E_DQ<28>
  VSS(77)  = GND
  DQ(24)  = M_E_DQ<24>
  VSS(76)  = GND
  DQS12P  = M_E_DQS_DP<12>
  DQS12N  = M_E_DQS_DN<12>
  VSS(75)  = GND
  DQ(30)  = M_E_DQ<30>
  VSS(74)  = GND
  DQ(26)  = M_E_DQ<26>
  VSS(73)  = GND
  CB(4)  = M_E_ECC<4>
  VSS(72)  = GND
  CB(0)  = M_E_ECC<0>
  VSS(71)  = GND
  DQS17P  = M_E_DQS_DP<17>
  DQS17N  = M_E_DQS_DN<17>
  VSS(70)  = GND
  CB(6)  = M_E_ECC<6>
  VSS(69)  = GND
  CB(2)  = M_E_ECC<2>
  VSS(68)  = GND
  RESET_N  = M_DEF_RST_N
  VDD(25)  = PVDDQ_DEF
  CKE(0)  = M_E_CKE<2>
  VDD(24)  = PVDDQ_DEF
  ACT_N  = M_E_ACT_N
  BG(0)  = M_E_BG<0>
  VDD(23)  = PVDDQ_DEF
  A12  = M_E_MA<12>
  A9  = M_E_MA<9>
  VDD(22)  = PVDDQ_DEF
  A8  = M_E_MA<8>
  A6  = M_E_MA<6>
  VDD(21)  = PVDDQ_DEF
  A3  = M_E_MA<3>
  A1  = M_E_MA<1>
  VDD(20)  = PVDDQ_DEF
  CK0P  = M_E_CLK_DP<2>
  CK0N  = M_E_CLK_DN<2>
  VDD(19)  = PVDDQ_DEF
  VTT(1)  = PVTT_DEF
  EVENT_N  = FM_DIMM_EVENT_COD_N
  A0  = M_E_MA<0>
  VDD(18)  = PVDDQ_DEF
  BA(0)  = M_E_BA<0>
  A16_RAS_N  = M_E_MA<16>
  VDD(17)  = PVDDQ_DEF
  S0_N  = M_E_CS_N<4>
  VDD(16)  = PVDDQ_DEF
  A15_CAS_N  = M_E_MA<15>
  ODT(0)  = M_E_ODT<2>
  VDD(15)  = PVDDQ_DEF
  S1_N  = M_E_CS_N<5>
  VDD(14)  = PVDDQ_DEF
  ODT(1)  = M_E_ODT<3>
  VDD(13)  = PVDDQ_DEF
  S2_N_C(0)  = M_E_CS_N<6>
  VSS(67)  = GND
  DQ(36)  = M_E_DQ<36>
  VSS(66)  = GND
  DQ(32)  = M_E_DQ<32>
  VSS(65)  = GND
  DQS13P  = M_E_DQS_DP<13>
  DQS13N  = M_E_DQS_DN<13>
  VSS(64)  = GND
  DQ(38)  = M_E_DQ<38>
  VSS(63)  = GND
  DQ(34)  = M_E_DQ<34>
  VSS(62)  = GND
  DQ(44)  = M_E_DQ<44>
  VSS(61)  = GND
  DQ(40)  = M_E_DQ<40>
  VSS(60)  = GND
  DQS14P  = M_E_DQS_DP<14>
  DQS14N  = M_E_DQS_DN<14>
  VSS(59)  = GND
  DQ(46)  = M_E_DQ<46>
  VSS(58)  = GND
  DQ(42)  = M_E_DQ<42>
  VSS(57)  = GND
  DQ(52)  = M_E_DQ<52>
  VSS(56)  = GND
  DQ(48)  = M_E_DQ<48>
  VSS(55)  = GND
  DQS15P  = M_E_DQS_DP<15>
  DQS15N  = M_E_DQS_DN<15>
  VSS(54)  = GND
  DQ(54)  = M_E_DQ<54>
  VSS(53)  = GND
  DQ(50)  = M_E_DQ<50>
  VSS(52)  = GND
  DQ(60)  = M_E_DQ<60>
  VSS(51)  = GND
  DQ(56)  = M_E_DQ<56>
  VSS(50)  = GND
  DQS16P  = M_E_DQS_DP<16>
  DQS16N  = M_E_DQS_DN<16>
  VSS(49)  = GND
  DQ(62)  = M_E_DQ<62>
  VSS(48)  = GND
  DQ(58)  = M_E_DQ<58>
  VSS(47)  = GND
  SA(0)  = PVPP_DEF
  SA(1)  = PVPP_DEF
  SCL  = SMB_DDR_DEF_VPP_SCL
  VPP(4)  = PVPP_DEF
  VPP(3)  = PVPP_DEF
  RFU(2)  = TP_CH_E_DIMM_E1_RFU_2
  \12v\(0)  = P12V_NVDIMM_DEF
  VREFCA  = M_E_VREF
  VSS(46)  = GND
  DQ(5)  = M_E_DQ<5>
  VSS(45)  = GND
  DQ(1)  = M_E_DQ<1>
  VSS(44)  = GND
  DQS0N  = M_E_DQS_DN<0>
  DQS0P  = M_E_DQS_DP<0>
  VSS(43)  = GND
  DQ(7)  = M_E_DQ<7>
  VSS(42)  = GND
  DQ(3)  = M_E_DQ<3>
  VSS(41)  = GND
  DQ(13)  = M_E_DQ<13>
  VSS(40)  = GND
  DQ(9)  = M_E_DQ<9>
  VSS(39)  = GND
  DQS1N  = M_E_DQS_DN<1>
  DQS1P  = M_E_DQS_DP<1>
  VSS(38)  = GND
  DQ(15)  = M_E_DQ<15>
  VSS(37)  = GND
  DQ(11)  = M_E_DQ<11>
  VSS(36)  = GND
  DQ(21)  = M_E_DQ<21>
  VSS(35)  = GND
  DQ(17)  = M_E_DQ<17>
  VSS(34)  = GND
  DQS2N  = M_E_DQS_DN<2>
  DQS2P  = M_E_DQS_DP<2>
  VSS(33)  = GND
  DQ(23)  = M_E_DQ<23>
  VSS(32)  = GND
  DQ(19)  = M_E_DQ<19>
  VSS(31)  = GND
  DQ(29)  = M_E_DQ<29>
  VSS(30)  = GND
  DQ(25)  = M_E_DQ<25>
  VSS(29)  = GND
  DQS3N  = M_E_DQS_DN<3>
  DQS3P  = M_E_DQS_DP<3>
  VSS(28)  = GND
  DQ(31)  = M_E_DQ<31>
  VSS(27)  = GND
  DQ(27)  = M_E_DQ<27>
  VSS(26)  = GND
  CB(5)  = M_E_ECC<5>
  VSS(25)  = GND
  CB(1)  = M_E_ECC<1>
  VSS(24)  = GND
  DQS8N  = M_E_DQS_DN<8>
  DQS8P  = M_E_DQS_DP<8>
  VSS(23)  = GND
  CB(7)  = M_E_ECC<7>
  VSS(22)  = GND
  CB(3)  = M_E_ECC<3>
  VSS(21)  = GND
  CKE(1)  = M_E_CKE<3>
  VDD(12)  = PVDDQ_DEF
  RFU(0)  = TP_CH_E_DIMM_E1_RFU_0
  VDD(11)  = PVDDQ_DEF
  BG(1)  = M_E_BG<1>
  ALERT_N  = M_E_ALERT_N
  VDD(10)  = PVDDQ_DEF
  A11  = M_E_MA<11>
  A7  = M_E_MA<7>
  VDD(9)  = PVDDQ_DEF
  A5  = M_E_MA<5>
  A4  = M_E_MA<4>
  VDD(8)  = PVDDQ_DEF
  A2  = M_E_MA<2>
  VDD(7)  = PVDDQ_DEF
  CK1P  = M_E_CLK_DP<3>
  CK1N  = M_E_CLK_DN<3>
  VDD(6)  = PVDDQ_DEF
  VTT(0)  = PVTT_DEF
  PAR  = M_E_PAR
  VDD(5)  = PVDDQ_DEF
  BA(1)  = M_E_BA<1>
  A10  = M_E_MA<10>
  VDD(4)  = PVDDQ_DEF
  RFU(1)  = TP_CH_E_DIMM_E1_RFU_1
  A14_WE_N  = M_E_MA<14>
  VDD(3)  = PVDDQ_DEF
  SAVE_N_NC  = FM_ADR_COMPLETE_DEF_N
  VDD(2)  = PVDDQ_DEF
  A13  = M_E_MA<13>
  VDD(1)  = PVDDQ_DEF
  A17  = M_E_MA<17>
  C(2)  = M_E_C<2>
  VDD(0)  = PVDDQ_DEF
  S3_N_C(1)  = M_E_CS_N<7>
  SA(2)  = GND
  VSS(20)  = GND
  DQ(37)  = M_E_DQ<37>
  VSS(19)  = GND
  DQ(33)  = M_E_DQ<33>
  VSS(18)  = GND
  DQS4N  = M_E_DQS_DN<4>
  DQS4P  = M_E_DQS_DP<4>
  VSS(17)  = GND
  DQ(39)  = M_E_DQ<39>
  VSS(16)  = GND
  DQ(35)  = M_E_DQ<35>
  VSS(15)  = GND
  DQ(45)  = M_E_DQ<45>
  VSS(14)  = GND
  DQ(41)  = M_E_DQ<41>
  VSS(13)  = GND
  DQS5N  = M_E_DQS_DN<5>
  DQS5P  = M_E_DQS_DP<5>
  VSS(12)  = GND
  DQ(47)  = M_E_DQ<47>
  VSS(11)  = GND
  DQ(43)  = M_E_DQ<43>
  VSS(10)  = GND
  DQ(53)  = M_E_DQ<53>
  VSS(9)  = GND
  DQ(49)  = M_E_DQ<49>
  VSS(8)  = GND
  DQS6N  = M_E_DQS_DN<6>
  DQS6P  = M_E_DQS_DP<6>
  VSS(7)  = GND
  DQ(55)  = M_E_DQ<55>
  VSS(6)  = GND
  DQ(51)  = M_E_DQ<51>
  VSS(5)  = GND
  DQ(61)  = M_E_DQ<61>
  VSS(4)  = GND
  DQ(57)  = M_E_DQ<57>
  VSS(3)  = GND
  DQS7N  = M_E_DQS_DN<7>
  DQS7P  = M_E_DQS_DP<7>
  VSS(2)  = GND
  DQ(63)  = M_E_DQ<63>
  VSS(1)  = GND
  DQ(59)  = M_E_DQ<59>
  VSS(0)  = GND
  VDDSPD  = PVPP_DEF
  SDA  = SMB_DDR_DEF_VPP_SDA
  VPP(1)  = PVPP_DEF
  VPP(0)  = PVPP_DEF
  VPP(2)  = PVPP_DEF

(kicad_pcb
	(version 20260206)
	(generator "pcbnew")
	(generator_version "10.0")
	(general
		(thickness 1.6)
		(legacy_teardrops no)
	)
	(paper "A4")
	(title_block
		(title "Wiwynn_Tioga_Pass_MB.brd")
		(comment 1 "Tioga Pass / footprint 3319 of 4770 (J6L2), pads 51-100 of 291")
	)
	(layers
		(0 "F.Cu" signal "TOP")
		(4 "In1.Cu" signal "L2GND")
		(6 "In2.Cu" signal "L3")
		(8 "In3.Cu" signal "L4GND")
		(10 "In4.Cu" signal "L5")
		(12 "In5.Cu" signal "L6GND")
		(14 "In6.Cu" signal "L7VCC")
		(16 "In7.Cu" signal "L8VCC")
		(18 "In8.Cu" signal "L9GND")
		(20 "In9.Cu" signal "L10")
		(22 "In10.Cu" signal "L11GND")
		(24 "In11.Cu" signal "L12")
		(26 "In12.Cu" signal "L13GND")
		(2 "B.Cu" signal "BOTTOM")
		(9 "F.Adhes" user "F.Adhesive")
		(11 "B.Adhes" user "B.Adhesive")
		(13 "F.Paste" user "Package Geometry/Pastemask Top")
		(15 "B.Paste" user "Package Geometry/Pastemask Bottom")
		(5 "F.SilkS" user "Ref Des/Silkscreen Top")
		(7 "B.SilkS" user "Ref Des/Silkscreen Bottom")
		(1 "F.Mask" user "Board Geometry/Soldermask Top")
		(3 "B.Mask" user "Board Geometry/Soldermask Bottom")
		(17 "Dwgs.User" user "User.Drawings")
		(19 "Cmts.User" user "User.Comments")
		(21 "Eco1.User" user "User.Eco1")
		(23 "Eco2.User" user "User.Eco2")
		(25 "Edge.Cuts" user "Board Geometry/Outline")
		(27 "Margin" user)
		(31 "F.CrtYd" user "Package Geometry/Place Bound Top")
		(29 "B.CrtYd" user "Package Geometry/Place Bound Bottom")
		(35 "F.Fab" user "Ref Des/Assembly Top")
		(33 "B.Fab" user "Ref Des/Assembly Bottom")
	)
	(footprint ""
		(layer "B.Cu")
		(at 194.700398 -142.477236 90)
		(property "Reference" "J6L2"
			(at 2.276348 38.21811 0)
			(unlocked yes)
			(layer "B.SilkS")
			(effects
				(font
					(size 0.7874 0.5842)
					(thickness 0.1524)
				)
				(justify left mirror)
			)
		)
		(property "Value" ""
			(at 0 0 90)
			(layer "B.Fab")
			(effects
				(font
					(size 1.27 1.27)
				)
				(justify mirror)
			)
		)
		(duplicate_pad_numbers_are_jumpers no)
		(pad "48" smd rect
			(at 0 39.949882 270)
			(size 1.8034 0.508)
			(layers "B.Cu" "B.Mask" "B.Paste")
			(net "GND")
		)
		(pad "49" smd rect
			(at 0 40.80002 270)
			(size 1.8034 0.508)
			(layers "B.Cu" "B.Mask" "B.Paste")
			(net "M_E_ECC<0>")
		)
		(pad "50" smd rect
			(at 0 41.649904 270)
			(size 1.8034 0.508)
			(layers "B.Cu" "B.Mask" "B.Paste")
			(net "GND")
		)
		(pad "51" smd rect
			(at 0 42.500042 270)
			(size 1.8034 0.508)
			(layers "B.Cu" "B.Mask" "B.Paste")
			(net "M_E_DQS_DP<17>")
		)
		(pad "52" smd rect
			(at 0 43.349926 270)
			(size 1.8034 0.508)
			(layers "B.Cu" "B.Mask" "B.Paste")
			(net "M_E_DQS_DN<17>")
		)
		(pad "53" smd rect
			(at 0 44.200064 270)
			(size 1.8034 0.508)
			(layers "B.Cu" "B.Mask" "B.Paste")
			(net "GND")
		)
		(pad "54" smd rect
			(at 0 45.049948 270)
			(size 1.8034 0.508)
			(layers "B.Cu" "B.Mask" "B.Paste")
			(net "M_E_ECC<6>")
		)
		(pad "55" smd rect
			(at 0 45.900086 270)
			(size 1.8034 0.508)
			(layers "B.Cu" "B.Mask" "B.Paste")
			(net "GND")
		)
		(pad "56" smd rect
			(at 0 46.74997 270)
			(size 1.8034 0.508)
			(layers "B.Cu" "B.Mask" "B.Paste")
			(net "M_E_ECC<2>")
		)
		(pad "57" smd rect
			(at 0 47.600108 270)
			(size 1.8034 0.508)
			(layers "B.Cu" "B.Mask" "B.Paste")
			(net "GND")
		)
		(pad "58" smd rect
			(at 0 48.449992 270)
			(size 1.8034 0.508)
			(layers "B.Cu" "B.Mask" "B.Paste")
			(net "M_DEF_RST_N")
		)
		(pad "59" smd rect
			(at 0 49.299876 270)
			(size 1.8034 0.508)
			(layers "B.Cu" "B.Mask" "B.Paste")
			(net "PVDDQ_DEF")
		)
		(pad "60" smd rect
			(at 0 50.150014 270)
			(size 1.8034 0.508)
			(layers "B.Cu" "B.Mask" "B.Paste")
			(net "M_E_CKE<2>")
		)
		(pad "61" smd rect
			(at 0 50.999898 270)
			(size 1.8034 0.508)
			(layers "B.Cu" "B.Mask" "B.Paste")
			(net "PVDDQ_DEF")
		)
		(pad "62" smd rect
			(at 0 51.850036 270)
			(size 1.8034 0.508)
			(layers "B.Cu" "B.Mask" "B.Paste")
			(net "M_E_ACT_N")
		)
		(pad "63" smd rect
			(at 0 52.69992 270)
			(size 1.8034 0.508)
			(layers "B.Cu" "B.Mask" "B.Paste")
			(net "M_E_BG<0>")
		)
		(pad "64" smd rect
			(at 0 53.550058 270)
			(size 1.8034 0.508)
			(layers "B.Cu" "B.Mask" "B.Paste")
			(net "PVDDQ_DEF")
		)
		(pad "65" smd rect
			(at 0 54.399942 270)
			(size 1.8034 0.508)
			(layers "B.Cu" "B.Mask" "B.Paste")
			(net "M_E_MA<12>")
		)
		(pad "66" smd rect
			(at 0 55.25008 270)
			(size 1.8034 0.508)
			(layers "B.Cu" "B.Mask" "B.Paste")
			(net "M_E_MA<9>")
		)
		(pad "67" smd rect
			(at 0 56.099964 270)
			(size 1.8034 0.508)
			(layers "B.Cu" "B.Mask" "B.Paste")
			(net "PVDDQ_DEF")
		)
		(pad "68" smd rect
			(at 0 56.950102 270)
			(size 1.8034 0.508)
			(layers "B.Cu" "B.Mask" "B.Paste")
			(net "M_E_MA<8>")
		)
		(pad "69" smd rect
			(at 0 57.799986 270)
			(size 1.8034 0.508)
			(layers "B.Cu" "B.Mask" "B.Paste")
			(net "M_E_MA<6>")
		)
		(pad "70" smd rect
			(at 0 58.650124 270)
			(size 1.8034 0.508)
			(layers "B.Cu" "B.Mask" "B.Paste")
			(net "PVDDQ_DEF")
		)
		(pad "71" smd rect
			(at 0 59.500008 270)
			(size 1.8034 0.508)
			(layers "B.Cu" "B.Mask" "B.Paste")
			(net "M_E_MA<3>")
		)
		(pad "72" smd rect
			(at 0 60.349892 270)
			(size 1.8034 0.508)
			(layers "B.Cu" "B.Mask" "B.Paste")
			(net "M_E_MA<1>")
		)
		(pad "73" smd rect
			(at 0 61.20003 270)
			(size 1.8034 0.508)
			(layers "B.Cu" "B.Mask" "B.Paste")
			(net "PVDDQ_DEF")
		)
		(pad "74" smd rect
			(at 0 62.049914 270)
			(size 1.8034 0.508)
			(layers "B.Cu" "B.Mask" "B.Paste")
			(net "M_E_CLK_DP<2>")
		)
		(pad "75" smd rect
			(at 0 62.900052 270)
			(size 1.8034 0.508)
			(layers "B.Cu" "B.Mask" "B.Paste")
			(net "M_E_CLK_DN<2>")
		)
		(pad "76" smd rect
			(at 0 63.749936 270)
			(size 1.8034 0.508)
			(layers "B.Cu" "B.Mask" "B.Paste")
			(net "PVDDQ_DEF")
		)
		(pad "77" smd rect
			(at 0 64.600074 270)
			(size 1.8034 0.508)
			(layers "B.Cu" "B.Mask" "B.Paste")
			(net "PVTT_DEF")
		)
		(pad "78" smd rect
			(at 0 70.550024 270)
			(size 1.8034 0.508)
			(layers "B.Cu" "B.Mask" "B.Paste")
			(net "FM_DIMM_EVENT_COD_N")
		)
		(pad "79" smd rect
			(at 0 71.399908 270)
			(size 1.8034 0.508)
			(layers "B.Cu" "B.Mask" "B.Paste")
			(net "M_E_MA<0>")
		)
		(pad "80" smd rect
			(at 0 72.250046 270)
			(size 1.8034 0.508)
			(layers "B.Cu" "B.Mask" "B.Paste")
			(net "PVDDQ_DEF")
		)
		(pad "81" smd rect
			(at 0 73.09993 270)
			(size 1.8034 0.508)
			(layers "B.Cu" "B.Mask" "B.Paste")
			(net "M_E_BA<0>")
		)
		(pad "82" smd rect
			(at 0 73.950068 270)
			(size 1.8034 0.508)
			(layers "B.Cu" "B.Mask" "B.Paste")
			(net "M_E_MA<16>")
		)
		(pad "83" smd rect
			(at 0 74.799952 270)
			(size 1.8034 0.508)
			(layers "B.Cu" "B.Mask" "B.Paste")
			(net "PVDDQ_DEF")
		)
		(pad "84" smd rect
			(at 0 75.65009 270)
			(size 1.8034 0.508)
			(layers "B.Cu" "B.Mask" "B.Paste")
			(net "M_E_CS_N<4>")
		)
		(pad "85" smd rect
			(at 0 76.499974 270)
			(size 1.8034 0.508)
			(layers "B.Cu" "B.Mask" "B.Paste")
			(net "PVDDQ_DEF")
		)
		(pad "86" smd rect
			(at 0 77.350112 270)
			(size 1.8034 0.508)
			(layers "B.Cu" "B.Mask" "B.Paste")
			(net "M_E_MA<15>")
		)
		(pad "87" smd rect
			(at 0 78.199996 270)
			(size 1.8034 0.508)
			(layers "B.Cu" "B.Mask" "B.Paste")
			(net "M_E_ODT<2>")
		)
		(pad "88" smd rect
			(at 0 79.04988 270)
			(size 1.8034 0.508)
			(layers "B.Cu" "B.Mask" "B.Paste")
			(net "PVDDQ_DEF")
		)
		(pad "89" smd rect
			(at 0 79.900018 270)
			(size 1.8034 0.508)
			(layers "B.Cu" "B.Mask" "B.Paste")
			(net "M_E_CS_N<5>")
		)
		(pad "90" smd rect
			(at 0 80.749902 270)
			(size 1.8034 0.508)
			(layers "B.Cu" "B.Mask" "B.Paste")
			(net "PVDDQ_DEF")
		)
		(pad "91" smd rect
			(at 0 81.60004 270)
			(size 1.8034 0.508)
			(layers "B.Cu" "B.Mask" "B.Paste")
			(net "M_E_ODT<3>")
		)
		(pad "92" smd rect
			(at 0 82.449924 270)
			(size 1.8034 0.508)
			(layers "B.Cu" "B.Mask" "B.Paste")
			(net "PVDDQ_DEF")
		)
		(pad "93" smd rect
			(at 0 83.300062 270)
			(size 1.8034 0.508)
			(layers "B.Cu" "B.Mask" "B.Paste")
			(net "M_E_CS_N<6>")
		)
		(pad "94" smd rect
			(at 0 84.149946 270)
			(size 1.8034 0.508)
			(layers "B.Cu" "B.Mask" "B.Paste")
			(net "GND")
		)
		(pad "95" smd rect
			(at 0 85.000084 270)
			(size 1.8034 0.508)
			(layers "B.Cu" "B.Mask" "B.Paste")
			(net "M_E_DQ<36>")
		)
		(pad "96" smd rect
			(at 0 85.849968 270)
			(size 1.8034 0.508)
			(layers "B.Cu" "B.Mask" "B.Paste")
			(net "GND")
		)
		(pad "97" smd rect
			(at 0 86.700106 270)
			(size 1.8034 0.508)
			(layers "B.Cu" "B.Mask" "B.Paste")
			(net "M_E_DQ<32>")
		)
	)
)
